(kicad_pcb
	(version 20221018)
	(generator pcbnew)
	(general
    (thickness 1.586)
  )
	(paper "A4")
	(title_block
    (date "2024-03-26")
    (rev "1.1.3")
		(comment 9 "footprints 38-46 of 146")
	)
	(layers
    (0 "F.Cu" signal)
    (1 "In1.Cu" power)
    (2 "In2.Cu" power)
    (31 "B.Cu" signal)
    (32 "B.Adhes" user "B.Adhesive")
    (33 "F.Adhes" user "F.Adhesive")
    (34 "B.Paste" user)
    (35 "F.Paste" user)
    (36 "B.SilkS" user "B.Silkscreen")
    (37 "F.SilkS" user "F.Silkscreen")
    (38 "B.Mask" user)
    (39 "F.Mask" user)
    (40 "Dwgs.User" user "User.Drawings")
    (41 "Cmts.User" user "User.Comments")
    (42 "Eco1.User" user "User.Eco1")
    (43 "Eco2.User" user "User.Eco2")
    (44 "Edge.Cuts" user)
    (45 "Margin" user)
    (46 "B.CrtYd" user "B.Courtyard")
    (47 "F.CrtYd" user "F.Courtyard")
    (48 "B.Fab" user)
    (49 "F.Fab" user)
  )
	(footprint "scalenode-cm4-baseboard-footprints:oshw-logo"
		(layer "F.Cu")
    (at 138.1 60.3)
    (descr "OSHW Logo")
    (tags "OSHW Logo")
    (property "Author" "Antmicro")
    (property "License" "Apache-2.0")
    (property "MPN" "")
    (property "Manufacturer" "")
    (property "Sheetfile" "scalenode-cm4-baseboard.kicad_sch")
    (property "Sheetname" "")
    (attr exclude_from_pos_files)
    (fp_text reference "N3" (at 2.175 -1.975) (layer "F.SilkS") hide
        (effects (font (size 0.7 0.7) (thickness 0.15)) (justify left bottom))
    )
    (fp_text value "oshw_logo" (at 0.1 -2.325) (layer "F.SilkS") hide
        (effects (font (size 0.7 0.7) (thickness 0.15)) (justify left bottom))
    )
  )
	(footprint "scalenode-cm4-baseboard-footprints:Switch_Slide_CAS-120TA" (layer "F.Cu")
    (at 120.6 59.4 180)
    (property "Author" "Antmicro")
    (property "License" "Apache-2.0")
    (property "MPN" "CAS-120TA")
    (property "Manufacturer" "Nidec Components")
    (property "Sheetfile" "interfaces.kicad_sch")
    (property "Sheetname" "Interfaces")
    (attr smd)
    (fp_text reference "S1" (at -1.25 -2.851 180) (layer "F.SilkS")
        (effects (font (size 0.7 0.7) (thickness 0.15)) (justify left bottom))
    )
    (fp_text value "CAS-120TA" (at 5.85 -0.325 180) (layer "F.Fab")
        (effects (font (size 0.7 0.7) (thickness 0.15)) (justify left bottom))
    )
    (fp_text user "License: Apache-2.0" (at -3.15 7.6 180) (layer "F.Fab") hide
        (effects (font (size 0.7 0.7) (thickness 0.15)) (justify left bottom))
    )
    (fp_text user "Author: Antmicro" (at -3.15 6.4 180) (layer "F.Fab") hide
        (effects (font (size 0.7 0.7) (thickness 0.15)) (justify left bottom))
    )
    (fp_text user "${REFERENCE}" (at -3.15 5.2 180) (layer "F.Fab") hide
        (effects (font (size 0.7 0.7) (thickness 0.15)) (justify left bottom))
    )
    (fp_circle (center -3.502 1.148) (end -3.452 1.148)
      (stroke (width 0.15) (type solid)) (fill solid) (layer "F.SilkS"))
    (fp_rect (start -3.202 -1.901) (end 3.2 1.898)
      (stroke (width 0.05) (type solid)) (fill none) (layer "F.CrtYd"))
    (fp_line (start -2.9 1.148) (end -2.9 -1.151)
      (stroke (width 0.15) (type solid)) (layer "F.Fab"))
    (fp_line (start -2.9 1.148) (end 2.898 1.148)
      (stroke (width 0.15) (type solid)) (layer "F.Fab"))
    (fp_line (start 2.898 -1.151) (end -2.9 -1.151)
      (stroke (width 0.15) (type solid)) (layer "F.Fab"))
    (fp_line (start 2.898 -1.151) (end 2.898 1.148)
      (stroke (width 0.15) (type solid)) (layer "F.Fab"))
    (pad "1" smd rect (at -1.75 1.148 180) (size 1 1.6) (layers "F.Cu" "F.Paste" "F.Mask")
      (net 27 "/Interfaces/VBus_Slave") (pinfunction "1") (pintype "passive"))
    (pad "2" smd rect (at 0 -1.151 180) (size 1 1.6) (layers "F.Cu" "F.Paste" "F.Mask")
      (net 244 "PROG_MODE") (pinfunction "2") (pintype "passive"))
    (pad "3" smd rect (at 1.749 1.148 180) (size 1 1.6) (layers "F.Cu" "F.Paste" "F.Mask")
      (net 215 "unconnected-(S1-Pad3)") (pinfunction "3") (pintype "passive+no_connect"))
  )
	(footprint "scalenode-cm4-baseboard-footprints:C_0402_1005Metric" (layer "F.Cu")
    (at 81.745 85.296 90)
    (descr "Capacitor SMD 0402")
    (tags "capacitor SMD 0402")
    (property "Author" "Antmicro")
    (property "Dielectric" "X5R")
    (property "License" "Apache-2.0")
    (property "MPN" "GRM155R61H104KE14D")
    (property "Manufacturer" "Murata")
    (property "Sheetfile" "interfaces.kicad_sch")
    (property "Sheetname" "Interfaces")
    (property "Val" "100n")
    (property "Voltage" "50V")
    (property "ki_description" " ")
    (attr smd)
    (fp_text reference "C56" (at -1.029 1.43 90) (layer "F.SilkS")
        (effects (font (size 0.7 0.7) (thickness 0.15)) (justify left bottom))
    )
    (fp_text value "C_100n_0402" (at 0 1.4 90) (layer "F.Fab")
        (effects (font (size 0.7 0.7) (thickness 0.15)) (justify left bottom))
    )
    (fp_text user "Author: Antmicro" (at -0.932 4.17 90) (layer "F.Fab") hide
        (effects (font (size 0.7 0.7) (thickness 0.15)) (justify left bottom))
    )
    (fp_text user "License: Apache-2.0" (at -0.932 5.17 90) (layer "F.Fab") hide
        (effects (font (size 0.7 0.7) (thickness 0.15)) (justify left bottom))
    )
    (fp_text user "${REFERENCE}" (at -0.932 3.168 90) (layer "F.Fab") hide
        (effects (font (size 0.7 0.7) (thickness 0.15)) (justify left bottom))
    )
    (fp_rect (start -0.94 -0.47) (end 0.94 0.47)
      (stroke (width 0.05) (type solid)) (fill none) (layer "F.CrtYd"))
    (fp_rect (start -0.499 -0.249) (end 0.499 0.249)
      (stroke (width 0.15) (type solid)) (fill none) (layer "F.Fab"))
    (pad "1" smd roundrect (at -0.484 0 90) (size 0.59 0.64) (layers "F.Cu" "F.Paste" "F.Mask") (roundrect_rratio 0.25)
      (net 27 "/Interfaces/VBus_Slave") (pintype "passive"))
    (pad "2" smd roundrect (at 0.484 0 90) (size 0.59 0.64) (layers "F.Cu" "F.Paste" "F.Mask") (roundrect_rratio 0.25)
      (net 11 "GND") (pintype "passive"))
  )
	(footprint "scalenode-cm4-baseboard-footprints:LED_0603_1608Metric_G" (layer "F.Cu")
    (at 76.1 81.541 -90)
    (descr "LED SMD 0603 Red")
    (tags "LED SMD 0603 Red")
    (property "Author" "Antmicro")
    (property "License" "Apache-2.0")
    (property "MPN" "598-8D80-107F")
    (property "Manufacturer" "Dialight")
    (property "Sheetfile" "compute-module.kicad_sch")
    (property "Sheetname" "Compute module")
    (attr smd)
    (fp_text reference "D11" (at 1.079 -1.37 -90) (layer "F.SilkS")
        (effects (font (size 0.7 0.7) (thickness 0.15)) (justify left bottom))
    )
    (fp_text value "LED_G_0603_598-8D80-107F" (at -5.041 -0.825 -90) (layer "F.Fab")
        (effects (font (size 0.7 0.7) (thickness 0.15)) (justify left bottom))
    )
    (fp_text user "Author: Antmicro" (at -1.31 4.769 -90) (layer "F.Fab") hide
        (effects (font (size 0.7 0.7) (thickness 0.15)) (justify left bottom))
    )
    (fp_text user "${REFERENCE}" (at -1.31 3.769 -90) (layer "F.Fab") hide
        (effects (font (size 0.7 0.7) (thickness 0.15)) (justify left bottom))
    )
    (fp_text user "License: Apache-2.0" (at -1.31 5.769 -90) (layer "F.Fab") hide
        (effects (font (size 0.7 0.7) (thickness 0.15)) (justify left bottom))
    )
    (fp_line (start -0.27 -0.3) (end 0.27 -0.3)
      (stroke (width 0.15) (type solid)) (layer "F.SilkS"))
    (fp_line (start -0.27 0.3) (end 0.27 0.3)
      (stroke (width 0.15) (type solid)) (layer "F.SilkS"))
    (fp_line (start 1.25 0.5) (end 1.25 -0.498)
      (stroke (width 0.15) (type solid)) (layer "F.SilkS"))
    (fp_rect (start 1.31 0.7) (end -1.31 -0.7)
      (stroke (width 0.05) (type solid)) (fill none) (layer "F.CrtYd"))
    (fp_line (start -0.599 0) (end -0.201 0)
      (stroke (width 0.15) (type solid)) (layer "F.Fab"))
    (fp_line (start -0.201 -0.2) (end -0.201 0)
      (stroke (width 0.15) (type solid)) (layer "F.Fab"))
    (fp_line (start -0.201 0) (end -0.201 0.202)
      (stroke (width 0.15) (type solid)) (layer "F.Fab"))
    (fp_line (start -0.201 0.202) (end 0.101 0)
      (stroke (width 0.15) (type solid)) (layer "F.Fab"))
    (fp_line (start 0.101 0) (end -0.201 -0.2)
      (stroke (width 0.15) (type solid)) (layer "F.Fab"))
    (fp_line (start 0.199 -0.2) (end 0.199 -0.1)
      (stroke (width 0.15) (type solid)) (layer "F.Fab"))
    (fp_line (start 0.199 0) (end 0.597 0)
      (stroke (width 0.15) (type solid)) (layer "F.Fab"))
    (fp_line (start 0.199 0.202) (end 0.199 -0.1)
      (stroke (width 0.15) (type solid)) (layer "F.Fab"))
    (fp_rect (start -0.848 -0.4) (end 0.85 0.402)
      (stroke (width 0.15) (type solid)) (fill none) (layer "F.Fab"))
    (pad "1" smd rect (at -0.75 0 90) (size 0.8 0.8) (layers "F.Cu" "F.Paste" "F.Mask")
      (net 232 "3V3_RPi") (pinfunction "1") (pintype "passive"))
    (pad "2" smd rect (at 0.75 0 90) (size 0.8 0.8) (layers "F.Cu" "F.Paste" "F.Mask")
      (net 233 "Net-(D11-Pad2)") (pinfunction "2") (pintype "passive"))
  )
	(footprint "scalenode-cm4-baseboard-footprints:UFDFN-6_1.45x1mm" (layer "F.Cu")
    (at 82.225 87.306 -90)
    (property "Author" "Antmicro")
    (property "License" "Apache-2.0")
    (property "MPN" "TPD4S012DRYR")
    (property "Manufacturer" "Texas Instruments")
    (property "Sheetfile" "interfaces.kicad_sch")
    (property "Sheetname" "Interfaces")
    (attr smd)
    (fp_text reference "D3" (at 0.444 -1.775 -90) (layer "F.SilkS")
        (effects (font (size 0.7 0.7) (thickness 0.15)) (justify left bottom))
    )
    (fp_text value "TPD4S012DRYR" (at 0 1.929 -90) (layer "F.Fab")
        (effects (font (size 0.7 0.7) (thickness 0.15)) (justify left bottom))
    )
    (fp_text user "${REFERENCE}" (at -0.98 3.929 -90) (layer "F.Fab") hide
        (effects (font (size 0.7 0.7) (thickness 0.15)) (justify left bottom))
    )
    (fp_text user "Author: Antmicro" (at -0.98 5.129 -90) (layer "F.Fab") hide
        (effects (font (size 0.7 0.7) (thickness 0.15)) (justify left bottom))
    )
    (fp_text user "License: Apache-2.0" (at -0.98 6.328 -90) (layer "F.Fab") hide
        (effects (font (size 0.7 0.7) (thickness 0.15)) (justify left bottom))
    )
    (fp_line (start -0.802 -0.6) (end -0.802 -0.5)
      (stroke (width 0.15) (type solid)) (layer "F.SilkS"))
    (fp_line (start -0.802 0.4) (end -0.802 0.598)
      (stroke (width 0.15) (type solid)) (layer "F.SilkS"))
    (fp_line (start -0.802 0.598) (end -0.701 0.598)
      (stroke (width 0.15) (type solid)) (layer "F.SilkS"))
    (fp_line (start -0.701 -0.6) (end -0.802 -0.6)
      (stroke (width 0.15) (type solid)) (layer "F.SilkS"))
    (fp_line (start -0.701 0.598) (end -0.701 0.699)
      (stroke (width 0.15) (type solid)) (layer "F.SilkS"))
    (fp_line (start 0.699 -0.6) (end 0.8 -0.6)
      (stroke (width 0.15) (type solid)) (layer "F.SilkS"))
    (fp_line (start 0.699 0.598) (end 0.8 0.598)
      (stroke (width 0.15) (type solid)) (layer "F.SilkS"))
    (fp_line (start 0.8 -0.6) (end 0.8 -0.5)
      (stroke (width 0.15) (type solid)) (layer "F.SilkS"))
    (fp_line (start 0.8 0.598) (end 0.8 0.498)
      (stroke (width 0.15) (type solid)) (layer "F.SilkS"))
    (fp_circle (center -1.526 0.39) (end -1.476 0.39)
      (stroke (width 0.15) (type solid)) (fill solid) (layer "F.SilkS"))
    (fp_line (start -0.98 -0.87) (end 0.96 -0.87)
      (stroke (width 0.05) (type solid)) (layer "F.CrtYd"))
    (fp_line (start -0.98 0.9) (end -0.98 -0.87)
      (stroke (width 0.05) (type solid)) (layer "F.CrtYd"))
    (fp_line (start -0.98 0.9) (end 0.96 0.9)
      (stroke (width 0.05) (type solid)) (layer "F.CrtYd"))
    (fp_line (start 0.96 0.9) (end 0.96 -0.87)
      (stroke (width 0.05) (type solid)) (layer "F.CrtYd"))
    (fp_line (start -0.725 0.4) (end -0.725 -0.5)
      (stroke (width 0.15) (type solid)) (layer "F.Fab"))
    (fp_line (start -0.725 0.4) (end -0.6 0.498)
      (stroke (width 0.15) (type solid)) (layer "F.Fab"))
    (fp_line (start -0.72 -0.5) (end 0.718 -0.5)
      (stroke (width 0.15) (type solid)) (layer "F.Fab"))
    (fp_line (start -0.6 0.498) (end 0.718 0.498)
      (stroke (width 0.15) (type solid)) (layer "F.Fab"))
    (fp_line (start 0.723 0.498) (end 0.723 -0.5)
      (stroke (width 0.15) (type solid)) (layer "F.Fab"))
    (pad "1" smd rect (at -0.5 0.39 270) (size 0.3 0.52) (layers "F.Cu" "F.Paste" "F.Mask")
      (net 235 "/Interfaces/CONN_USB_N") (pinfunction "D+") (pintype "input") (solder_mask_margin 0.05))
    (pad "2" smd rect (at 0 0.373 270) (size 0.3 0.49) (layers "F.Cu" "F.Paste" "F.Mask")
      (net 236 "/Interfaces/CONN_USB_P") (pinfunction "D-") (pintype "output") (solder_mask_margin 0.05))
    (pad "3" smd rect (at 0.498 0.373 270) (size 0.3 0.49) (layers "F.Cu" "F.Paste" "F.Mask")
      (net 35 "unconnected-(D3-ID-Pad3)") (pinfunction "ID") (pintype "input+no_connect") (solder_mask_margin 0.05))
    (pad "4" smd rect (at 0.498 -0.375 270) (size 0.3 0.49) (layers "F.Cu" "F.Paste" "F.Mask")
      (net 11 "GND") (pinfunction "GND") (pintype "power_in") (solder_mask_margin 0.05))
    (pad "5" smd rect (at 0 -0.375 270) (size 0.3 0.49) (layers "F.Cu" "F.Paste" "F.Mask")
      (net 161 "unconnected-(D3-NC-Pad5)") (pinfunction "NC") (pintype "no_connect") (solder_mask_margin 0.05))
    (pad "6" smd rect (at -0.5 -0.375 270) (size 0.3 0.49) (layers "F.Cu" "F.Paste" "F.Mask")
      (net 27 "/Interfaces/VBus_Slave") (pinfunction "V_{BUS}") (pintype "power_in") (solder_mask_margin 0.05))
  )
	(footprint "scalenode-cm4-baseboard-footprints:R_0603_1608Metric" (layer "F.Cu")
    (at 79.22 81.76 180)
    (descr "Resistor SMD 0603")
    (tags "resistor SMD 0603")
    (property "Author" "Antmicro")
    (property "License" "Apache-2.0")
    (property "MPN" "CR0603-FX-1001ELF")
    (property "Manufacturer" "Bourns")
    (property "Sheetfile" "compute-module.kicad_sch")
    (property "Sheetname" "Compute module")
    (property "Tolerance" "1%")
    (property "Val" "1k")
    (property "ki_description" "1k resistor in 0603 package with 1% tolerance")
    (attr smd)
    (fp_text reference "R42" (at 1.03 0.73) (layer "F.SilkS")
        (effects (font (size 0.7 0.7) (thickness 0.15)) (justify left bottom))
    )
    (fp_text value "R_1k_0603" (at 0 1.6 180) (layer "F.Fab")
        (effects (font (size 0.7 0.7) (thickness 0.15)) (justify left bottom))
    )
    (fp_text user "Author: Antmicro" (at -1.25 4.9 180) (layer "F.Fab") hide
        (effects (font (size 0.7 0.7) (thickness 0.15)) (justify left bottom))
    )
    (fp_text user "License: Apache-2.0" (at -1.25 5.9 180) (layer "F.Fab") hide
        (effects (font (size 0.7 0.7) (thickness 0.15)) (justify left bottom))
    )
    (fp_text user "${REFERENCE}" (at -1.25 3.898 180) (layer "F.Fab") hide
        (effects (font (size 0.7 0.7) (thickness 0.15)) (justify left bottom))
    )
    (fp_line (start -0.3 -0.3) (end 0.3 -0.3)
      (stroke (width 0.15) (type solid)) (layer "F.SilkS"))
    (fp_line (start -0.3 0.3) (end 0.3 0.3)
      (stroke (width 0.15) (type solid)) (layer "F.SilkS"))
    (fp_rect (start -1.25 -0.7) (end 1.25 0.7)
      (stroke (width 0.05) (type solid)) (fill none) (layer "F.CrtYd"))
    (fp_rect (start -0.8 -0.4) (end 0.8 0.4)
      (stroke (width 0.15) (type solid)) (fill none) (layer "F.Fab"))
    (pad "1" smd roundrect (at -0.7 0 180) (size 0.6 0.8) (layers "F.Cu" "F.Paste" "F.Mask") (roundrect_rratio 0.2)
      (net 227 "Net-(J7-Pad21)") (pintype "passive"))
    (pad "2" smd roundrect (at 0.7 0 180) (size 0.6 0.8) (layers "F.Cu" "F.Paste" "F.Mask") (roundrect_rratio 0.2)
      (net 233 "Net-(D11-Pad2)") (pintype "passive"))
  )
	(footprint "scalenode-cm4-baseboard-footprints:TP_SMD_1mm" (layer "F.Cu")
    (at 138.8 69)
    (property "Author" "Antmicro")
    (property "License" "Apache-2.0")
    (property "MPN" "")
    (property "Manufacturer" "")
    (property "Sheetfile" "supply.kicad_sch")
    (property "Sheetname" "Supply")
    (property "ki_description" "Test Point 1mm")
    (attr exclude_from_pos_files)
    (fp_text reference "TP7" (at 0 -0.731898) (layer "F.SilkS") hide
        (effects (font (size 0.7 0.7) (thickness 0.15)) (justify left bottom))
    )
    (fp_text value "TP_1mm_SMD" (at 0 1.4) (layer "F.Fab")
        (effects (font (size 0.7 0.7) (thickness 0.15)) (justify left bottom))
    )
    (fp_text user "${REFERENCE}" (at -0.5 2.8) (layer "F.Fab") hide
        (effects (font (size 0.7 0.7) (thickness 0.15)) (justify left bottom))
    )
    (fp_text user "License: Apache-2.0" (at -0.5 5.2) (layer "F.Fab") hide
        (effects (font (size 0.7 0.7) (thickness 0.15)) (justify left bottom))
    )
    (fp_text user "Author: Antmicro" (at -0.5 4) (layer "F.Fab") hide
        (effects (font (size 0.7 0.7) (thickness 0.15)) (justify left bottom))
    )
    (pad "1" smd circle (at 0 0) (size 1 1) (layers "F.Cu" "F.Mask")
      (net 170 "3V3_SSD") (pinfunction "1") (pintype "passive"))
  )
	(footprint "scalenode-cm4-baseboard-footprints:C_2220_5650Metric" (layer "F.Cu")
    (at 110.4 92.06)
    (descr "Capacitor SMD 2220")
    (tags "capacitor SMD 2220")
    (property "Author" "Antmicro")
    (property "Dielectric" "X7S")
    (property "License" "Apache-2.0")
    (property "MPN" "C5750X7S2A226M280KB")
    (property "Manufacturer" "TDK")
    (property "Sheetfile" "poe.kicad_sch")
    (property "Sheetname" "PoE")
    (property "Val" "22u")
    (property "Voltage" "100V")
    (property "ki_description" " ")
    (attr smd)
    (fp_text reference "C29" (at -1.15 3.69) (layer "F.SilkS")
        (effects (font (size 0.7 0.7) (thickness 0.15)) (justify left bottom))
    )
    (fp_text value "C_22u_100V_2220" (at 0 3.9) (layer "F.Fab")
        (effects (font (size 0.7 0.7) (thickness 0.15)) (justify left bottom))
    )
    (fp_text user "Author: Antmicro" (at -3.7 7.9) (layer "F.Fab") hide
        (effects (font (size 0.7 0.7) (thickness 0.15)) (justify left bottom))
    )
    (fp_text user "License: Apache-2.0" (at -3.7 6.9) (layer "F.Fab") hide
        (effects (font (size 0.7 0.7) (thickness 0.15)) (justify left bottom))
    )
    (fp_text user "${REFERENCE}" (at -3.7 5.9) (layer "F.Fab") hide
        (effects (font (size 0.7 0.7) (thickness 0.15)) (justify left bottom))
    )
    (fp_line (start -1.415 -2.61) (end 1.415 -2.61)
      (stroke (width 0.15) (type solid)) (layer "F.SilkS"))
    (fp_line (start -1.415 2.61) (end 1.415 2.61)
      (stroke (width 0.15) (type solid)) (layer "F.SilkS"))
    (fp_rect (start -3.7 -2.95) (end 3.7 2.95)
      (stroke (width 0.05) (type solid)) (fill none) (layer "F.CrtYd"))
    (fp_rect (start -2.85 -2.5) (end 2.85 2.5)
      (stroke (width 0.15) (type solid)) (fill none) (layer "F.Fab"))
    (pad "1" smd roundrect (at -2.55 0) (size 1.8 5.4) (layers "F.Cu" "F.Paste" "F.Mask") (roundrect_rratio 0.138889)
      (net 4 "GNDD") (pintype "passive"))
    (pad "2" smd roundrect (at 2.55 0) (size 1.8 5.4) (layers "F.Cu" "F.Paste" "F.Mask") (roundrect_rratio 0.138889)
      (net 6 "/PoE/VDD_POE_IN") (pintype "passive"))
  )
	(footprint "scalenode-cm4-baseboard-footprints:R_0805_2012Metric" (layer "F.Cu")
    (at 98.9 92.6)
    (property "Author" "Antmicro")
    (property "License" "Apache-2.0")
    (property "MPN" "CR0805-FX-3242ELF")
    (property "Manufacturer" "Bourns")
    (property "Sheetfile" "poe.kicad_sch")
    (property "Sheetname" "PoE")
    (property "Tolerance" "1%")
    (property "Val" "32k4")
    (property "ki_description" "32k4 resistor in 0805 package with 1% tolerance")
    (attr smd)
    (fp_text reference "R33" (at 1.75 0.425) (layer "F.SilkS")
        (effects (font (size 0.7 0.7) (thickness 0.15)) (justify left bottom))
    )
    (fp_text value "R_32k4_0805" (at 0 1.8) (layer "F.Fab")
        (effects (font (size 0.7 0.7) (thickness 0.15)) (justify left bottom))
    )
    (fp_text user "Author: Antmicro" (at -1.9 4.4) (layer "F.Fab") hide
        (effects (font (size 0.7 0.7) (thickness 0.15)) (justify left bottom))
    )
    (fp_text user "${REFERENCE}" (at -1.9 3.1) (layer "F.Fab") hide
        (effects (font (size 0.7 0.7) (thickness 0.15)) (justify left bottom))
    )
    (fp_text user "License: Apache-2.0" (at -1.9 5.75) (layer "F.Fab") hide
        (effects (font (size 0.7 0.7) (thickness 0.15)) (justify left bottom))
    )
    (fp_line (start -0.32 0.699) (end 0.28 0.699)
      (stroke (width 0.15) (type solid)) (layer "F.SilkS"))
    (fp_line (start -0.3 -0.701) (end 0.298 -0.701)
      (stroke (width 0.15) (type solid)) (layer "F.SilkS"))
    (fp_rect (start -1.75 -0.85) (end 1.75 0.85)
      (stroke (width 0.05) (type solid)) (fill none) (layer "F.CrtYd"))
    (fp_line (start -0.951 -0.682) (end 0.949 -0.682)
      (stroke (width 0.15) (type solid)) (layer "F.Fab"))
    (fp_line (start -0.951 -0.677) (end -0.951 0.675)
      (stroke (width 0.15) (type solid)) (layer "F.Fab"))
    (fp_line (start -0.951 0.68) (end 0.949 0.68)
      (stroke (width 0.15) (type solid)) (layer "F.Fab"))
    (fp_line (start 0.949 -0.677) (end 0.949 0.675)
      (stroke (width 0.15) (type solid)) (layer "F.Fab"))
    (pad "1" smd roundrect (at -1.1 -0.001) (size 1 1.4) (layers "F.Cu" "F.Paste" "F.Mask") (roundrect_rratio 0.15)
      (net 21 "Net-(D7-Pad1)") (pintype "passive"))
    (pad "2" smd roundrect (at 1.1 -0.001) (size 1 1.4) (layers "F.Cu" "F.Paste" "F.Mask") (roundrect_rratio 0.15)
      (net 6 "/PoE/VDD_POE_IN") (pintype "passive"))
  )
)
